# T6G (Grand Teton) — schematic netlist excerpt (pin names and nets, part order shuffled) for the footprints in the layout excerpt that follows; sources: Cadence DE-HDL packaged netlist, KiCad conversion of 04192023_DAF0TMB3IC0_F0TG_MB_C_brd_V02_OCP.brd

L3  Q_INDUCTOR  BLM21SN300SN1D/5A IND  pkg SMLF  page 323 : \1\ = P1V8_CPU1_RT_1D ; \2\ = P1V8_CPU1_RT0_1A
C2408  Q_CAP  22UF 4V 20% X6S  pkg C0402  page 74 : A = PVDDCR_SOC_P1 ; B = GND
PC7  Q_CAP  0.1UF 25V 10% X7R  pkg 0402  page 193 : A = PVDDCR_CPU0_P0_VINSEN ; B = GND

(kicad_pcb
	(version 20260206)
	(generator "pcbnew")
	(generator_version "10.0")
	(general
		(thickness 1.6)
		(legacy_teardrops no)
	)
	(paper "A4")
	(title_block
		(title "04192023_DAF0TMB3IC0_F0TG_MB_C_brd_V02_OCP.brd")
		(comment 1 "Grand Teton / footprints 6723-6725 of 8354")
	)
	(layers
		(0 "F.Cu" signal "TOP")
		(4 "In1.Cu" signal "GND")
		(6 "In2.Cu" signal "IN1")
		(8 "In3.Cu" signal "GND1")
		(10 "In4.Cu" signal "IN2")
		(12 "In5.Cu" signal "GND2")
		(14 "In6.Cu" signal "IN3")
		(16 "In7.Cu" signal "GND3")
		(18 "In8.Cu" signal "VCC")
		(20 "In9.Cu" signal "VCC1")
		(22 "In10.Cu" signal "GND4")
		(24 "In11.Cu" signal "IN4")
		(26 "In12.Cu" signal "GND5")
		(28 "In13.Cu" signal "IN5")
		(30 "In14.Cu" signal "GND6")
		(32 "In15.Cu" signal "IN6")
		(34 "In16.Cu" signal "GND7")
		(2 "B.Cu" signal "BOTTOM")
		(9 "F.Adhes" user "F.Adhesive")
		(11 "B.Adhes" user "B.Adhesive")
		(13 "F.Paste" user "Package Geometry/Pastemask Top")
		(15 "B.Paste" user "Package Geometry/Pastemask Bottom")
		(5 "F.SilkS" user "Ref Des/Silkscreen Top")
		(7 "B.SilkS" user "Ref Des/Silkscreen Bottom")
		(1 "F.Mask" user "Board Geometry/Soldermask Top")
		(3 "B.Mask" user "Board Geometry/Soldermask Bottom")
		(17 "Dwgs.User" user "User.Drawings")
		(19 "Cmts.User" user "User.Comments")
		(21 "Eco1.User" user "User.Eco1")
		(23 "Eco2.User" user "User.Eco2")
		(25 "Edge.Cuts" user "Board Geometry/Outline")
		(27 "Margin" user)
		(31 "F.CrtYd" user "Package Geometry/Place Bound Top")
		(29 "B.CrtYd" user "Package Geometry/Place Bound Bottom")
		(35 "F.Fab" user "Ref Des/Assembly Top")
		(33 "B.Fab" user "Ref Des/Assembly Bottom")
	)
	(footprint ""
		(layer "B.Cu")
		(at 107.675934 -256.012442 -90)
		(property "Reference" "C2408"
			(at 0 0 90)
			(layer "B.SilkS")
			(hide yes)
			(effects
				(font
					(size 1.27 1.27)
				)
				(justify mirror)
			)
		)
		(property "Value" ""
			(at 0 0 90)
			(layer "B.Fab")
			(effects
				(font
					(size 1.27 1.27)
				)
				(justify mirror)
			)
		)
		(duplicate_pad_numbers_are_jumpers no)
		(fp_line
			(start -0.7874 0.4064)
			(end 0.7874 0.4064)
			(stroke
				(width 0.1524)
				(type default)
			)
			(layer "B.SilkS")
		)
		(fp_line
			(start 0.7874 0.4064)
			(end 0.7874 -0.4064)
			(stroke
				(width 0.1524)
				(type default)
			)
			(layer "B.SilkS")
		)
		(fp_line
			(start -0.7874 -0.4064)
			(end -0.7874 0.4064)
			(stroke
				(width 0.1524)
				(type default)
			)
			(layer "B.SilkS")
		)
		(fp_line
			(start 0.7874 -0.4064)
			(end -0.7874 -0.4064)
			(stroke
				(width 0.1524)
				(type default)
			)
			(layer "B.SilkS")
		)
		(fp_line
			(start -0.67945 0.3048)
			(end -0.120396 0.3048)
			(stroke
				(width 0.1)
				(type default)
			)
			(layer "B.Fab")
		)
		(fp_line
			(start -0.120396 0.3048)
			(end -0.120396 0.2794)
			(stroke
				(width 0.1)
				(type default)
			)
			(layer "B.Fab")
		)
		(fp_line
			(start 0.12065 0.3048)
			(end 0.67945 0.3048)
			(stroke
				(width 0.1)
				(type default)
			)
			(layer "B.Fab")
		)
		(fp_line
			(start 0.67945 0.3048)
			(end 0.67945 -0.305054)
			(stroke
				(width 0.1)
				(type default)
			)
			(layer "B.Fab")
		)
		(fp_line
			(start -0.120396 0.2794)
			(end 0.12065 0.2794)
			(stroke
				(width 0.1)
				(type default)
			)
			(layer "B.Fab")
		)
		(fp_line
			(start 0.12065 0.2794)
			(end 0.12065 0.3048)
			(stroke
				(width 0.1)
				(type default)
			)
			(layer "B.Fab")
		)
		(fp_line
			(start -0.12065 -0.2794)
			(end -0.12065 -0.3048)
			(stroke
				(width 0.1)
				(type default)
			)
			(layer "B.Fab")
		)
		(fp_line
			(start 0.12065 -0.2794)
			(end -0.12065 -0.2794)
			(stroke
				(width 0.1)
				(type default)
			)
			(layer "B.Fab")
		)
		(fp_line
			(start -0.67945 -0.3048)
			(end -0.67945 0.3048)
			(stroke
				(width 0.1)
				(type default)
			)
			(layer "B.Fab")
		)
		(fp_line
			(start -0.12065 -0.3048)
			(end -0.67945 -0.3048)
			(stroke
				(width 0.1)
				(type default)
			)
			(layer "B.Fab")
		)
		(fp_line
			(start 0.12065 -0.305054)
			(end 0.12065 -0.2794)
			(stroke
				(width 0.1)
				(type default)
			)
			(layer "B.Fab")
		)
		(fp_line
			(start 0.67945 -0.305054)
			(end 0.12065 -0.305054)
			(stroke
				(width 0.1)
				(type default)
			)
			(layer "B.Fab")
		)
		(pad "1" smd circle
			(at 0.40005 0 90)
			(size 0 0)
			(layers "B.Cu" "B.Mask" "B.Paste")
			(net "PVDDCR_SOC_P1")
		)
		(pad "2" smd circle
			(at -0.40005 0 90)
			(size 0 0)
			(layers "B.Cu" "B.Mask" "B.Paste")
			(net "GND")
		)
	)
	(footprint ""
		(layer "B.Cu")
		(at 384.113278 -139.186158 180)
		(property "Reference" "PC7"
			(at 0 0 0)
			(layer "B.SilkS")
			(hide yes)
			(effects
				(font
					(size 1.27 1.27)
				)
				(justify mirror)
			)
		)
		(property "Value" ""
			(at 0 0 0)
			(layer "B.Fab")
			(effects
				(font
					(size 1.27 1.27)
				)
				(justify mirror)
			)
		)
		(duplicate_pad_numbers_are_jumpers no)
		(fp_line
			(start 0.7874 0.4064)
			(end 0.7874 -0.4064)
			(stroke
				(width 0.1524)
				(type default)
			)
			(layer "B.SilkS")
		)
		(fp_line
			(start 0.7874 -0.4064)
			(end -0.7874 -0.4064)
			(stroke
				(width 0.1524)
				(type default)
			)
			(layer "B.SilkS")
		)
		(fp_line
			(start -0.7874 0.4064)
			(end 0.7874 0.4064)
			(stroke
				(width 0.1524)
				(type default)
			)
			(layer "B.SilkS")
		)
		(fp_line
			(start -0.7874 -0.4064)
			(end -0.7874 0.4064)
			(stroke
				(width 0.1524)
				(type default)
			)
			(layer "B.SilkS")
		)
		(fp_line
			(start 0.67945 0.3048)
			(end 0.67945 -0.305054)
			(stroke
				(width 0.1)
				(type default)
			)
			(layer "B.Fab")
		)
		(fp_line
			(start 0.67945 -0.305054)
			(end 0.12065 -0.305054)
			(stroke
				(width 0.1)
				(type default)
			)
			(layer "B.Fab")
		)
		(fp_line
			(start 0.12065 0.3048)
			(end 0.67945 0.3048)
			(stroke
				(width 0.1)
				(type default)
			)
			(layer "B.Fab")
		)
		(fp_line
			(start 0.12065 0.2794)
			(end 0.12065 0.3048)
			(stroke
				(width 0.1)
				(type default)
			)
			(layer "B.Fab")
		)
		(fp_line
			(start 0.12065 -0.2794)
			(end -0.12065 -0.2794)
			(stroke
				(width 0.1)
				(type default)
			)
			(layer "B.Fab")
		)
		(fp_line
			(start 0.12065 -0.305054)
			(end 0.12065 -0.2794)
			(stroke
				(width 0.1)
				(type default)
			)
			(layer "B.Fab")
		)
		(fp_line
			(start -0.120396 0.3048)
			(end -0.120396 0.2794)
			(stroke
				(width 0.1)
				(type default)
			)
			(layer "B.Fab")
		)
		(fp_line
			(start -0.120396 0.2794)
			(end 0.12065 0.2794)
			(stroke
				(width 0.1)
				(type default)
			)
			(layer "B.Fab")
		)
		(fp_line
			(start -0.12065 -0.2794)
			(end -0.12065 -0.3048)
			(stroke
				(width 0.1)
				(type default)
			)
			(layer "B.Fab")
		)
		(fp_line
			(start -0.12065 -0.3048)
			(end -0.67945 -0.3048)
			(stroke
				(width 0.1)
				(type default)
			)
			(layer "B.Fab")
		)
		(fp_line
			(start -0.67945 0.3048)
			(end -0.120396 0.3048)
			(stroke
				(width 0.1)
				(type default)
			)
			(layer "B.Fab")
		)
		(fp_line
			(start -0.67945 -0.3048)
			(end -0.67945 0.3048)
			(stroke
				(width 0.1)
				(type default)
			)
			(layer "B.Fab")
		)
		(pad "1" smd circle
			(at 0.40005 0)
			(size 0 0)
			(layers "B.Cu" "B.Mask" "B.Paste")
			(net "PVDDCR_CPU0_P0_VINSEN")
		)
		(pad "2" smd circle
			(at -0.40005 0)
			(size 0 0)
			(layers "B.Cu" "B.Mask" "B.Paste")
			(net "GND")
		)
	)
	(footprint ""
		(layer "B.Cu")
		(at 70.252336 -384.575558)
		(property "Reference" "L3"
			(at 0 0 0)
			(layer "B.SilkS")
			(hide yes)
			(effects
				(font
					(size 1.27 1.27)
				)
				(justify mirror)
			)
		)
		(property "Value" ""
			(at 0 0 0)
			(layer "B.Fab")
			(effects
				(font
					(size 1.27 1.27)
				)
				(justify mirror)
			)
		)
		(duplicate_pad_numbers_are_jumpers no)
		(fp_line
			(start -1.63576 -0.8128)
			(end -1.63576 0.8128)
			(stroke
				(width 0.1524)
				(type default)
			)
			(layer "B.SilkS")
		)
		(fp_line
			(start -1.63576 0.8128)
			(end 1.63576 0.8128)
			(stroke
				(width 0.1524)
				(type default)
			)
			(layer "B.SilkS")
		)
		(fp_line
			(start 1.63576 -0.8128)
			(end -1.63576 -0.8128)
			(stroke
				(width 0.1524)
				(type default)
			)
			(layer "B.SilkS")
		)
		(fp_line
			(start 1.63576 -0.8128)
			(end 1.63576 0.8128)
			(stroke
				(width 0.1524)
				(type default)
			)
			(layer "B.SilkS")
		)
		(fp_line
			(start -1.560576 -0.738632)
			(end 1.56083 -0.738632)
			(stroke
				(width 0.1)
				(type default)
			)
			(layer "B.Fab")
		)
		(fp_line
			(start -1.560576 0.7366)
			(end -1.560576 -0.738632)
			(stroke
				(width 0.1)
				(type default)
			)
			(layer "B.Fab")
		)
		(fp_line
			(start -1.524 0.7366)
			(end -1.560576 0.7366)
			(stroke
				(width 0.1)
				(type default)
			)
			(layer "B.Fab")
		)
		(fp_line
			(start 1.524 0.7366)
			(end -1.524 0.7366)
			(stroke
				(width 0.1)
				(type default)
			)
			(layer "B.Fab")
		)
		(fp_line
			(start 1.56083 -0.738632)
			(end 1.56083 0.7366)
			(stroke
				(width 0.1)
				(type default)
			)
			(layer "B.Fab")
		)
		(fp_line
			(start 1.56083 0.7366)
			(end 1.524 0.7366)
			(stroke
				(width 0.1)
				(type default)
			)
			(layer "B.Fab")
		)
		(pad "1" smd rect
			(at 0.94996 0)
			(size 1.1176 1.3716)
			(layers "B.Cu" "B.Mask" "B.Paste")
			(net "P1V8_CPU1_RT_1D")
		)
		(pad "2" smd rect
			(at -0.94996 0)
			(size 1.1176 1.3716)
			(layers "B.Cu" "B.Mask" "B.Paste")
			(net "P1V8_CPU1_RT0_1A")
		)
	)
)
